# S9S_MB_2U (Grand Teton) — schematic parts with pin connectivity, parts 5876–5876 of 6093; source: Cadence DE-HDL packaged netlist (pstxprt.dat, pstxnet.dat, pstchip.dat)

U1  SOCKET4677_AZIF0045P001C01CS  SOCKET4677_AZIF0045-P001C01CS IO  pkg SOCKET4677_82X64-5XA_H466  page 44  (pins 328-654 of 4677)
  AG64  VSS144  POWER  = GND
  AG66  DDR2_SA_DQ14  BI  = M_C_CPU1_SA_DQ<14>
  AG68  DDR2_SA_DQ11  BI  = M_C_CPU1_SA_DQ<11>
  AG70  VSS145  POWER  = GND
  AG72  DDR3_SA_DQ6  BI  = M_D_CPU1_SA_DQ<6>
  AG74  DDR3_SA_DQ3  BI  = M_D_CPU1_SA_DQ<3>
  AG76  VSS146  POWER  = GND
  AG78  VCCFA_EHV_FIVRA9  POWER  = PVCCFA_EHV_FIVRA_CPU1
  AG80  UPI2_RX_DP8  IN  = UPI_CPU0_CPU1_P2P2_DP<8>
  AG82  UPI2_RX_DN11  IN  = UPI_CPU0_CPU1_P2P2_DN<11>
  AG84  VSS147  POWER  = GND
  AG86  PE4_TX_DN8  OUT  = P5E_CPU1_PE4_TX_DN<8>
  AG88  VSS148  POWER  = GND
  AG90  PE4_RX_DP8  IN  = P5E_CPU1_PE4_RX_DP<8>
  AH2  UPI0_TX_DN9  OUT  = UPI_CPU1_CPU0_P0P1_DN<9>
  AH4  VSS159  POWER  = GND
  AH6  UPI0_RX_DN9  IN  = UPI_CPU0_CPU1_P1P0_DN<9>
  AH8  VSS174  POWER  = GND
  AH10  PE0_RX_DP9  IN  = P5E_CPU1_PE0_RX_DP<9>
  AH12  VSS150  POWER  = GND
  AH14  PE0_TX_DP8  OUT  = P5E_CPU1_PE0_TX_DP<8>
  AH16  VSS151  POWER  = GND
  AH18  DDR2_SB_DQS_DP8  BI  = M_C_CPU1_SB_DQS_DP<8>
  AH20  VSS152  POWER  = GND
  AH22  VSS153  POWER  = GND
  AH24  DDR3_SB_DQS_DP7  BI  = M_D_CPU1_SB_DQS_DP<7>
  AH26  VSS154  POWER  = GND
  AH28  VSS155  POWER  = GND
  AH30  DDR2_SB_DQS_DP6  BI  = M_C_CPU1_SB_DQS_DP<6>
  AH32  VSS156  POWER  = GND
  AH34  VSS157  POWER  = GND
  AH36  DDR2_SB_DQS_DP5  BI  = M_C_CPU1_SB_DQS_DP<5>
  AH38  VSS158  POWER  = GND
  AH40  VSS160  POWER  = GND
  AH42  DDR3_SB_PAR  OUT  = M_D_CPU1_SB_PAR
  AH44  VSS161  POWER  = GND
  AH47  VSS162  POWER  = GND
  AH49  DDR2_CLK_DP1  OUT  = M_C_CPU1_CLK_DP<1>
  AH51  VSS163  POWER  = GND
  AH53  VSS164  POWER  = GND
  AH55  DDR2_SA_DQS_DN9  BI  = M_C_CPU1_SA_DQS_DN<9>
  AH57  VSS165  POWER  = GND
  AH59  VSS166  POWER  = GND
  AH61  DDR2_SA_DQS_DP8  BI  = M_C_CPU1_SA_DQS_DP<8>
  AH63  VSS167  POWER  = GND
  AH65  VSS168  POWER  = GND
  AH67  DDR2_SA_DQS_DN6  BI  = M_C_CPU1_SA_DQS_DN<6>
  AH69  VSS169  POWER  = GND
  AH71  VSS170  POWER  = GND
  AH73  DDR3_SA_DQS_DN5  BI  = M_D_CPU1_SA_DQS_DN<5>
  AH75  VSS171  POWER  = GND
  AH77  VSS172  POWER  = GND
  AH79  VSS173  POWER  = GND
  AH81  UPI2_RX_DP10  IN  = UPI_CPU0_CPU1_P2P2_DP<10>
  AH83  VSS175  POWER  = GND
  AH85  VCCFA_EHV_FIVRA10  POWER  = PVCCFA_EHV_FIVRA_CPU1
  AH87  PE4_TX_DP8  OUT  = P5E_CPU1_PE4_TX_DP<8>
  AH89  VCCFA_EHV_FIVRA11  POWER  = PVCCFA_EHV_FIVRA_CPU1
  AH91  PE4_RX_DN8  IN  = P5E_CPU1_PE4_RX_DN<8>
  AJ1  UPI0_TX_DP10  OUT  = UPI_CPU1_CPU0_P0P1_DP<10>
  AJ3  VCCFA_EHV2  POWER  = PVCCFA_EHV_CPU1
  AJ5  UPI0_RX_DP9  IN  = UPI_CPU0_CPU1_P1P0_DP<9>
  AJ7  VCCFA_EHV_FIVRA14  POWER  = PVCCFA_EHV_FIVRA_CPU1
  AJ9  PE0_RX_DN9  IN  = P5E_CPU1_PE0_RX_DN<9>
  AJ11  VCCFA_EHV_FIVRA12  POWER  = PVCCFA_EHV_FIVRA_CPU1
  AJ13  PE0_TX_DN8  OUT  = P5E_CPU1_PE0_TX_DN<8>
  AJ15  VCCFA_EHV_FIVRA13  POWER  = PVCCFA_EHV_FIVRA_CPU1
  AJ17  DDR2_SB_DQ31  BI  = M_C_CPU1_SB_DQ<31>
  AJ19  VSS176  POWER  = GND
  AJ21  DDR3_SB_DQS_DN3  BI  = M_D_CPU1_SB_DQS_DN<3>
  AJ23  VSS177  POWER  = GND
  AJ25  VSS178  POWER  = GND
  AJ27  DDR3_SB_DQS_DN1  BI  = M_D_CPU1_SB_DQS_DN<1>
  AJ29  VSS179  POWER  = GND
  AJ31  VSS180  POWER  = GND
  AJ33  DDR3_SB_DQS_DN0  BI  = M_D_CPU1_SB_DQS_DN<0>
  AJ35  VSS181  POWER  = GND
  AJ37  VSS182  POWER  = GND
  AJ39  DDR3_SB_DQS_DN9  BI  = M_D_CPU1_SB_DQS_DN<9>
  AJ41  VSS183  POWER  = GND
  AJ43  VSS184  POWER  = GND
  AJ45  DDR3_CLK_DN0  OUT  = M_D_CPU1_CLK_DN<0>
  AJ48  VSS185  POWER  = GND
  AJ50  VSS186  POWER  = GND
  AJ52  DDR3_SA_CA0  OUT  = M_D_CPU1_SA_CA<0>
  AJ54  VSS187  POWER  = GND
  AJ56  VSS188  POWER  = GND
  AJ58  DDR3_SA_DQS_DN4  BI  = M_D_CPU1_SA_DQS_DN<4>
  AJ60  VSS189  POWER  = GND
  AJ62  VSS190  POWER  = GND
  AJ64  DDR3_SA_DQS_DN3  BI  = M_D_CPU1_SA_DQS_DN<3>
  AJ66  VSS191  POWER  = GND
  AJ68  VSS192  POWER  = GND
  AJ70  DDR3_SA_DQS_DN2  BI  = M_D_CPU1_SA_DQS_DN<2>
  AJ72  VSS193  POWER  = GND
  AJ74  VSS194  POWER  = GND
  AJ76  DDR3_SA_DQS_DN1  BI  = M_D_CPU1_SA_DQS_DN<1>
  AJ78  VSS195  POWER  = GND
  AJ80  UPI2_RX_DN10  IN  = UPI_CPU0_CPU1_P2P2_DN<10>
  AJ82  UPI2_RX_DP11  IN  = UPI_CPU0_CPU1_P2P2_DP<11>
  AJ84  VSS196  POWER  = GND
  AJ86  PE4_TX_DN9  OUT  = P5E_CPU1_PE4_TX_DN<9>
  AJ88  VSS197  POWER  = GND
  AJ90  PE4_RX_DP9  IN  = P5E_CPU1_PE4_RX_DP<9>
  AK2  UPI0_TX_DN10  OUT  = UPI_CPU1_CPU0_P0P1_DN<10>
  AK4  VSS204  POWER  = GND
  AK6  UPI0_RX_DN10  IN  = UPI_CPU0_CPU1_P1P0_DN<10>
  AK8  VSS212  POWER  = GND
  AK10  PE0_RX_DN10  IN  = P5E_CPU1_PE0_RX_DN<10>
  AK12  VSS198  POWER  = GND
  AK14  PE0_TX_DN9  OUT  = P5E_CPU1_PE0_TX_DN<9>
  AK16  VSS199  POWER  = GND
  AK18  VSS200  POWER  = GND
  AK20  DDR3_SB_DQ28  BI  = M_D_CPU1_SB_DQ<28>
  AK22  DDR3_SB_DQ25  BI  = M_D_CPU1_SB_DQ<25>
  AK24  VSS201  POWER  = GND
  AK26  DDR3_SB_DQ12  BI  = M_D_CPU1_SB_DQ<12>
  AK28  DDR3_SB_DQ9  BI  = M_D_CPU1_SB_DQ<9>
  AK30  VSS202  POWER  = GND
  AK32  DDR3_SB_DQ4  BI  = M_D_CPU1_SB_DQ<4>
  AK34  DDR3_SB_DQ1  BI  = M_D_CPU1_SB_DQ<1>
  AK36  VSS203  POWER  = GND
  AK38  DDR3_SB_ECC0  BI  = M_D_CPU1_SB_CB<0>
  AK40  DDR3_SB_ECC5  BI  = M_D_CPU1_SB_CB<5>
  AK42  VSS205  POWER  = GND
  AK44  DDR3_SB_CA0  OUT  = M_D_CPU1_SB_CA<0>
  AK47  DDR1_A_RSP1  IN  = M_B_CPU1_SA_RSP<1>
  AK49  VSS206  POWER  = GND
  AK51  DDR3_SA_CA2  OUT  = M_D_CPU1_SA_CA<2>
  AK53  DDR3_SA_CS_N1  OUT  = M_D_CPU1_SA_CS_N<1>
  AK55  VSS207  POWER  = GND
  AK57  DDR3_SA_ECC4  BI  = M_D_CPU1_SA_CB<4>
  AK59  DDR3_SA_ECC1  BI  = M_D_CPU1_SA_CB<1>
  AK61  VSS208  POWER  = GND
  AK63  DDR3_SA_DQ28  BI  = M_D_CPU1_SA_DQ<28>
  AK65  DDR3_SA_DQ25  BI  = M_D_CPU1_SA_DQ<25>
  AK67  VSS209  POWER  = GND
  AK69  DDR3_SA_DQ20  BI  = M_D_CPU1_SA_DQ<20>
  AK71  DDR3_SA_DQ17  BI  = M_D_CPU1_SA_DQ<17>
  AK73  VSS210  POWER  = GND
  AK75  DDR3_SA_DQ12  BI  = M_D_CPU1_SA_DQ<12>
  AK77  DDR3_SA_DQ9  BI  = M_D_CPU1_SA_DQ<9>
  AK79  VSS211  POWER  = GND
  AK81  VSS213  POWER  = GND
  AK83  VSS214  POWER  = GND
  AK85  PE4_TX_DP9  OUT  = P5E_CPU1_PE4_TX_DP<9>
  AK87  VSS215  POWER  = GND
  AK89  PE4_RX_DN9  IN  = P5E_CPU1_PE4_RX_DN<9>
  AK91  VSS216  POWER  = GND
  AL1  VSS217  POWER  = GND
  AL3  UPI0_TX_DP11  OUT  = UPI_CPU1_CPU0_P0P1_DP<11>
  AL5  VSS220  POWER  = GND
  AL7  UPI0_RX_DP10  IN  = UPI_CPU0_CPU1_P1P0_DP<10>
  AL9  VSS226  POWER  = GND
  AL11  PE0_RX_DP10  IN  = P5E_CPU1_PE0_RX_DP<10>
  AL13  VSS218  POWER  = GND
  AL15  PE0_TX_DP9  OUT  = P5E_CPU1_PE0_TX_DP<9>
  AL17  VSS219  POWER  = GND
  AL19  DDR3_SB_DQ29  BI  = M_D_CPU1_SB_DQ<29>
  AL21  DDR3_SB_DQS_DP3  BI  = M_D_CPU1_SB_DQS_DP<3>
  AL23  DDR3_SB_DQ24  BI  = M_D_CPU1_SB_DQ<24>
  AL25  DDR3_SB_DQ13  BI  = M_D_CPU1_SB_DQ<13>
  AL27  DDR3_SB_DQS_DP1  BI  = M_D_CPU1_SB_DQS_DP<1>
  AL29  DDR3_SB_DQ8  BI  = M_D_CPU1_SB_DQ<8>
  AL31  DDR3_SB_DQ5  BI  = M_D_CPU1_SB_DQ<5>
  AL33  DDR3_SB_DQS_DP0  BI  = M_D_CPU1_SB_DQS_DP<0>
  AL35  DDR3_SB_DQ0  BI  = M_D_CPU1_SB_DQ<0>
  AL37  DDR3_SB_ECC1  BI  = M_D_CPU1_SB_CB<1>
  AL39  DDR3_SB_DQS_DP9  BI  = M_D_CPU1_SB_DQS_DP<9>
  AL41  DDR3_SB_ECC4  BI  = M_D_CPU1_SB_CB<4>
  AL43  DDR3_SB_CA1  OUT  = M_D_CPU1_SB_CA<1>
  AL45  DDR3_CLK_DP0  OUT  = M_D_CPU1_CLK_DP<0>
  AL48  DDR1_A_RSP0  IN  = M_B_CPU1_SA_RSP<0>
  AL50  DDR3_SA_CA4  OUT  = M_D_CPU1_SA_CA<4>
  AL52  VSS221  POWER  = GND
  AL54  DDR3_SA_CS_N0  OUT  = M_D_CPU1_SA_CS_N<0>
  AL56  DDR3_SA_ECC5  BI  = M_D_CPU1_SA_CB<5>
  AL58  DDR3_SA_DQS_DP4  BI  = M_D_CPU1_SA_DQS_DP<4>
  AL60  DDR3_SA_ECC0  BI  = M_D_CPU1_SA_CB<0>
  AL62  DDR3_SA_DQ29  BI  = M_D_CPU1_SA_DQ<29>
  AL64  DDR3_SA_DQS_DP3  BI  = M_D_CPU1_SA_DQS_DP<3>
  AL66  DDR3_SA_DQ24  BI  = M_D_CPU1_SA_DQ<24>
  AL68  DDR3_SA_DQ21  BI  = M_D_CPU1_SA_DQ<21>
  AL70  DDR3_SA_DQS_DP2  BI  = M_D_CPU1_SA_DQS_DP<2>
  AL72  DDR3_SA_DQ16  BI  = M_D_CPU1_SA_DQ<16>
  AL74  DDR3_SA_DQ13  BI  = M_D_CPU1_SA_DQ<13>
  AL76  DDR3_SA_DQS_DP1  BI  = M_D_CPU1_SA_DQS_DP<1>
  AL78  DDR3_SA_DQ8  BI  = M_D_CPU1_SA_DQ<8>
  AL80  VSS222  POWER  = GND
  AL82  VSS223  POWER  = GND
  AL84  VSS224  POWER  = GND
  AL86  PE4_TX_DN10  OUT  = P5E_CPU1_PE4_TX_DN<10>
  AL88  VSS225  POWER  = GND
  AL90  PE4_RX_DP10  IN  = P5E_CPU1_PE4_RX_DP<10>
  AM2  UPI0_TX_DN11  OUT  = UPI_CPU1_CPU0_P0P1_DN<11>
  AM4  VSS240  POWER  = GND
  AM6  UPI0_RX_DP11  IN  = UPI_CPU0_CPU1_P1P0_DP<11>
  AM8  VSS260  POWER  = GND
  AM10  PE0_RX_DN11  IN  = P5E_CPU1_PE0_RX_DN<11>
  AM12  VSS227  POWER  = GND
  AM14  PE0_TX_DP10  OUT  = P5E_CPU1_PE0_TX_DP<10>
  AM16  VSS228  POWER  = GND
  AM18  VSS229  POWER  = GND
  AM20  VSS230  POWER  = GND
  AM22  VSS231  POWER  = GND
  AM24  VSS232  POWER  = GND
  AM26  VSS233  POWER  = GND
  AM28  VSS234  POWER  = GND
  AM30  VSS235  POWER  = GND
  AM32  VSS236  POWER  = GND
  AM34  VSS237  POWER  = GND
  AM36  VSS238  POWER  = GND
  AM38  VSS239  POWER  = GND
  AM40  VSS241  POWER  = GND
  AM42  VSS242  POWER  = GND
  AM44  VSS243  POWER  = GND
  AM47  VSS244  POWER  = GND
  AM49  VSS245  POWER  = GND
  AM51  VSS246  POWER  = GND
  AM53  VSS247  POWER  = GND
  AM55  VSS248  POWER  = GND
  AM57  VSS249  POWER  = GND
  AM59  VSS250  POWER  = GND
  AM61  VSS251  POWER  = GND
  AM63  VSS252  POWER  = GND
  AM65  VSS253  POWER  = GND
  AM67  VSS254  POWER  = GND
  AM69  VSS255  POWER  = GND
  AM71  VSS256  POWER  = GND
  AM73  VSS257  POWER  = GND
  AM75  VSS258  POWER  = GND
  AM77  VSS259  POWER  = GND
  AM79  VCCFA_EHV_FIVRA15  POWER  = PVCCFA_EHV_FIVRA_CPU1
  AM81  UPI2_TX_DN12  OUT  = UPI_CPU1_CPU0_P2P2_DN<12>
  AM83  UPI2_TX_DP13  OUT  = UPI_CPU1_CPU0_P2P2_DP<13>
  AM85  VCCFA_EHV_FIVRA16  POWER  = PVCCFA_EHV_FIVRA_CPU1
  AM87  PE4_TX_DP10  OUT  = P5E_CPU1_PE4_TX_DP<10>
  AM89  VCCFA_EHV_FIVRA17  POWER  = PVCCFA_EHV_FIVRA_CPU1
  AM91  PE4_RX_DN10  IN  = P5E_CPU1_PE4_RX_DN<10>
  AN1  UPI0_TX_DP12  OUT  = UPI_CPU1_CPU0_P0P1_DP<12>
  AN3  VCCFA_EHV3  POWER  = PVCCFA_EHV_CPU1
  AN5  UPI0_RX_DN11  IN  = UPI_CPU0_CPU1_P1P0_DN<11>
  AN7  VCCFA_EHV_FIVRA20  POWER  = PVCCFA_EHV_FIVRA_CPU1
  AN9  PE0_RX_DP11  IN  = P5E_CPU1_PE0_RX_DP<11>
  AN11  VCCFA_EHV_FIVRA18  POWER  = PVCCFA_EHV_FIVRA_CPU1
  AN13  PE0_TX_DN10  OUT  = P5E_CPU1_PE0_TX_DN<10>
  AN15  VCCFA_EHV_FIVRA19  POWER  = PVCCFA_EHV_FIVRA_CPU1
  AN17  RSVD2  BI  = NC_CPU1_UPI0_APROBE<0>
  AN19  DDR3_SB_DQ31  BI  = M_D_CPU1_SB_DQ<31>
  AN21  DDR3_SB_DQS_DN8  BI  = M_D_CPU1_SB_DQS_DN<8>
  AN23  DDR3_SB_DQ26  BI  = M_D_CPU1_SB_DQ<26>
  AN25  DDR3_SB_DQ15  BI  = M_D_CPU1_SB_DQ<15>
  AN27  DDR3_SB_DQS_DN6  BI  = M_D_CPU1_SB_DQS_DN<6>
  AN29  DDR3_SB_DQ10  BI  = M_D_CPU1_SB_DQ<10>
  AN31  DDR3_SB_DQ7  BI  = M_D_CPU1_SB_DQ<7>
  AN33  DDR3_SB_DQS_DN5  BI  = M_D_CPU1_SB_DQS_DN<5>
  AN35  DDR3_SB_DQ2  BI  = M_D_CPU1_SB_DQ<2>
  AN37  DDR3_SB_ECC3  BI  = M_D_CPU1_SB_CB<3>
  AN39  DDR3_SB_DQS_DP4  BI  = M_D_CPU1_SB_DQS_DP<4>
  AN41  DDR3_SB_ECC6  BI  = M_D_CPU1_SB_CB<6>
  AN43  DDR3_SA_CA6  OUT  = M_D_CPU1_SA_CA<6>
  AN45  DDR3_CLK_DN1  OUT  = M_D_CPU1_CLK_DN<1>
  AN48  DDR1_B_RSP0  IN  = M_B_CPU1_SB_RSP<0>
  AN50  DDR3_SA_CA5  OUT  = M_D_CPU1_SA_CA<5>
  AN52  VSS261  POWER  = GND
  AN54  DDR3_SA_CS_N2  OUT  = M_D_CPU1_SA_CS_N<2>
  AN56  DDR3_SA_ECC7  BI  = M_D_CPU1_SA_CB<7>
  AN58  DDR3_SA_DQS_DN9  BI  = M_D_CPU1_SA_DQS_DN<9>
  AN60  DDR3_SA_ECC2  BI  = M_D_CPU1_SA_CB<2>
  AN62  DDR3_SA_DQ31  BI  = M_D_CPU1_SA_DQ<31>
  AN64  DDR3_SA_DQS_DN8  BI  = M_D_CPU1_SA_DQS_DN<8>
  AN66  DDR3_SA_DQ26  BI  = M_D_CPU1_SA_DQ<26>
  AN68  DDR3_SA_DQ23  BI  = M_D_CPU1_SA_DQ<23>
  AN70  DDR3_SA_DQS_DN7  BI  = M_D_CPU1_SA_DQS_DN<7>
  AN72  DDR3_SA_DQ18  BI  = M_D_CPU1_SA_DQ<18>
  AN74  DDR3_SA_DQ15  BI  = M_D_CPU1_SA_DQ<15>
  AN76  DDR3_SA_DQS_DN6  BI  = M_D_CPU1_SA_DQS_DN<6>
  AN78  DDR3_SA_DQ10  BI  = M_D_CPU1_SA_DQ<10>
  AN80  VCCFA_EHV_FIVRA21  POWER  = PVCCFA_EHV_FIVRA_CPU1
  AN82  UPI2_TX_DN13  OUT  = UPI_CPU1_CPU0_P2P2_DN<13>
  AN84  VSS262  POWER  = GND
  AN86  PE4_TX_DP11  OUT  = P5E_CPU1_PE4_TX_DP<11>
  AN88  VSS263  POWER  = GND
  AN90  PE4_RX_DP11  IN  = P5E_CPU1_PE4_RX_DP<11>
  AP2  UPI0_TX_DN12  OUT  = UPI_CPU1_CPU0_P0P1_DN<12>
  AP4  VSS270  POWER  = GND
  AP6  UPI0_RX_DN12  IN  = UPI_CPU0_CPU1_P1P0_DN<12>
  AP8  VSS278  POWER  = GND
  AP10  PE0_RX_DN12  IN  = P5E_CPU1_PE0_RX_DN<12>
  AP12  VSS264  POWER  = GND
  AP14  PE0_TX_DN11  OUT  = P5E_CPU1_PE0_TX_DN<11>
  AP16  VSS265  POWER  = GND
  AP18  VSS266  POWER  = GND
  AP20  DDR3_SB_DQ30  BI  = M_D_CPU1_SB_DQ<30>
  AP22  DDR3_SB_DQ27  BI  = M_D_CPU1_SB_DQ<27>
  AP24  VSS267  POWER  = GND
  AP26  DDR3_SB_DQ14  BI  = M_D_CPU1_SB_DQ<14>
  AP28  DDR3_SB_DQ11  BI  = M_D_CPU1_SB_DQ<11>
  AP30  VSS268  POWER  = GND
  AP32  DDR3_SB_DQ6  BI  = M_D_CPU1_SB_DQ<6>
  AP34  DDR3_SB_DQ3  BI  = M_D_CPU1_SB_DQ<3>
  AP36  VSS269  POWER  = GND
  AP38  DDR3_SB_ECC2  BI  = M_D_CPU1_SB_CB<2>
  AP40  DDR3_SB_ECC7  BI  = M_D_CPU1_SB_CB<7>
  AP42  VSS271  POWER  = GND
  AP44  DDR3_SA_PAR  OUT  = M_D_CPU1_SA_PAR
  AP47  DDR1_B_RSP1  IN  = M_B_CPU1_SB_RSP<1>
  AP49  VSS272  POWER  = GND
  AP51  DDR3_SA_CA3  OUT  = M_D_CPU1_SA_CA<3>
  AP53  DDR3_SA_CS_N3  OUT  = M_D_CPU1_SA_CS_N<3>
  AP55  VSS273  POWER  = GND
  AP57  DDR3_SA_ECC6  BI  = M_D_CPU1_SA_CB<6>
  AP59  DDR3_SA_ECC3  BI  = M_D_CPU1_SA_CB<3>
  AP61  VSS274  POWER  = GND
  AP63  DDR3_SA_DQ30  BI  = M_D_CPU1_SA_DQ<30>
  AP65  DDR3_SA_DQ27  BI  = M_D_CPU1_SA_DQ<27>
  AP67  VSS275  POWER  = GND
  AP69  DDR3_SA_DQ22  BI  = M_D_CPU1_SA_DQ<22>
  AP71  DDR3_SA_DQ19  BI  = M_D_CPU1_SA_DQ<19>
  AP73  VSS276  POWER  = GND
  AP75  DDR3_SA_DQ14  BI  = M_D_CPU1_SA_DQ<14>
  AP77  DDR3_SA_DQ11  BI  = M_D_CPU1_SA_DQ<11>
  AP79  VSS277  POWER  = GND
  AP81  UPI2_TX_DP12  OUT  = UPI_CPU1_CPU0_P2P2_DP<12>
  AP83  VSS279  POWER  = GND
  AP85  PE4_TX_DN11  OUT  = P5E_CPU1_PE4_TX_DN<11>
  AP87  VSS280  POWER  = GND
